# S9S_MB_2U (Grand Teton) — schematic netlist excerpt (pin names and nets, part order shuffled) for the footprints in the layout excerpt that follows; sources: Cadence DE-HDL packaged netlist, KiCad conversion of 03242023_DA0F0TMBIJ0_F0T_Motherboard_J_brd_V01_OCP.brd

X23  TP_TDR_4P_FTS  TP_TDR_4P_DIP EMPTY  pkg TH  page 309
  S1  = TDR_DIFF_100_IN4_DN
  P1  = T1_GND
  P2  = T1_GND
  S2  = TDR_DIFF_100_IN4_DP

PR1796  Q_RES  0 5% CHIP  pkg 0402LF  page 293 : A = PVCCINFAON_CPU1_VOS1 ; B = PVCCINFAON_CPU1

(kicad_pcb
	(version 20260206)
	(generator "pcbnew")
	(generator_version "10.0")
	(general
		(thickness 1.6)
		(legacy_teardrops no)
	)
	(paper "A4")
	(title_block
		(title "03242023_DA0F0TMBIJ0_F0T_Motherboard_J_brd_V01_OCP.brd")
		(comment 1 "Grand Teton / footprints 6064-6065 of 6105")
	)
	(layers
		(0 "F.Cu" signal "TOP")
		(4 "In1.Cu" signal "GND")
		(6 "In2.Cu" signal "IN1")
		(8 "In3.Cu" signal "GND1")
		(10 "In4.Cu" signal "IN2")
		(12 "In5.Cu" signal "GND2")
		(14 "In6.Cu" signal "IN3")
		(16 "In7.Cu" signal "GND3")
		(18 "In8.Cu" signal "VCC")
		(20 "In9.Cu" signal "VCC1")
		(22 "In10.Cu" signal "GND4")
		(24 "In11.Cu" signal "IN4")
		(26 "In12.Cu" signal "GND5")
		(28 "In13.Cu" signal "IN5")
		(30 "In14.Cu" signal "GND6")
		(32 "In15.Cu" signal "IN6")
		(34 "In16.Cu" signal "GND7")
		(2 "B.Cu" signal "BOTTOM")
		(9 "F.Adhes" user "F.Adhesive")
		(11 "B.Adhes" user "B.Adhesive")
		(13 "F.Paste" user "Package Geometry/Pastemask Top")
		(15 "B.Paste" user "Package Geometry/Pastemask Bottom")
		(5 "F.SilkS" user "Ref Des/Silkscreen Top")
		(7 "B.SilkS" user "Ref Des/Silkscreen Bottom")
		(1 "F.Mask" user "Board Geometry/Soldermask Top")
		(3 "B.Mask" user "Board Geometry/Soldermask Bottom")
		(17 "Dwgs.User" user "User.Drawings")
		(19 "Cmts.User" user "User.Comments")
		(21 "Eco1.User" user "User.Eco1")
		(23 "Eco2.User" user "User.Eco2")
		(25 "Edge.Cuts" user "Board Geometry/Outline")
		(27 "Margin" user)
		(31 "F.CrtYd" user "Package Geometry/Place Bound Top")
		(29 "B.CrtYd" user "Package Geometry/Place Bound Bottom")
		(35 "F.Fab" user "Ref Des/Assembly Top")
		(33 "B.Fab" user "Ref Des/Assembly Bottom")
	)
	(footprint ""
		(layer "B.Cu")
		(at 517.258808 -148.1328 -90)
		(property "Reference" "X23"
			(at 3.671824 3.308096 270)
			(unlocked yes)
			(layer "B.SilkS")
			(effects
				(font
					(size 0.7874 0.5842)
					(thickness 0.1524)
				)
				(justify left mirror)
			)
		)
		(property "Value" ""
			(at 0 0 90)
			(layer "B.Fab")
			(effects
				(font
					(size 1.27 1.27)
				)
				(justify mirror)
			)
		)
		(property "Device Type" "TP_TDR_4P_FTS_TH-TP_TDR_4P_DIPA"
			(at -1.30175 1.27 180)
			(unlocked yes)
			(layer "B.Fab")
			(hide yes)
			(effects
				(font
					(size 0.635 0.4064)
					(thickness 0.1524)
				)
				(justify mirror)
			)
		)
		(property "User Part Number" "N_A"
			(at -1.30175 1.27 180)
			(unlocked yes)
			(layer "Cmts.User")
			(hide yes)
			(effects
				(font
					(size 0.635 0.4064)
					(thickness 0.1524)
				)
				(justify mirror)
			)
		)
		(duplicate_pad_numbers_are_jumpers no)
		(fp_line
			(start -2.54 3.81)
			(end -2.54 3.6703)
			(stroke
				(width 0.1524)
				(type default)
			)
			(layer "B.SilkS")
		)
		(fp_line
			(start 0 3.81)
			(end -2.54 3.81)
			(stroke
				(width 0.1524)
				(type default)
			)
			(layer "B.SilkS")
		)
		(fp_line
			(start 0 3.175)
			(end 0 3.81)
			(stroke
				(width 0.1524)
				(type default)
			)
			(layer "B.SilkS")
		)
		(fp_line
			(start -2.54 1.4097)
			(end -2.54 1.1303)
			(stroke
				(width 0.1524)
				(type default)
			)
			(layer "B.SilkS")
		)
		(fp_line
			(start 0 0.635)
			(end 0 1.905)
			(stroke
				(width 0.1524)
				(type default)
			)
			(layer "B.SilkS")
		)
		(fp_line
			(start -2.54 -1.1303)
			(end -2.54 -1.27)
			(stroke
				(width 0.1524)
				(type default)
			)
			(layer "B.SilkS")
		)
		(fp_line
			(start -2.54 -1.27)
			(end 0 -1.27)
			(stroke
				(width 0.1524)
				(type default)
			)
			(layer "B.SilkS")
		)
		(fp_line
			(start 0 -1.27)
			(end 0 -0.635)
			(stroke
				(width 0.1524)
				(type default)
			)
			(layer "B.SilkS")
		)
		(fp_poly
			(pts
				(xy 2.895346 -0.6985) (xy 2.895346 0.8255) (xy 1.371346 0.0635)
			)
			(stroke
				(width 0)
				(type default)
			)
			(fill yes)
			(layer "B.SilkS")
		)
		(fp_line
			(start -2.54 3.81)
			(end -2.54 -1.27)
			(stroke
				(width 0.1)
				(type default)
			)
			(layer "B.Fab")
		)
		(fp_line
			(start 0 3.81)
			(end -2.54 3.81)
			(stroke
				(width 0.1)
				(type default)
			)
			(layer "B.Fab")
		)
		(fp_line
			(start -2.54 -1.27)
			(end 0 -1.27)
			(stroke
				(width 0.1)
				(type default)
			)
			(layer "B.Fab")
		)
		(fp_line
			(start 0 -1.27)
			(end 0 3.81)
			(stroke
				(width 0.1)
				(type default)
			)
			(layer "B.Fab")
		)
		(fp_poly
			(pts
				(xy 0.761746 0) (xy 2.285746 -0.762) (xy 2.285746 0.762)
			)
			(stroke
				(width 0)
				(type default)
			)
			(fill yes)
			(layer "B.Fab")
		)
		(pad "1" thru_hole circle
			(at 0 0 90)
			(size 1.0033 1.0033)
			(drill 0.249936)
			(layers "*.Cu" "*.Mask")
			(remove_unused_layers no)
			(net "TDR_DIFF_100_IN4_DN")
			(clearance 0.10795)
			(padstack
				(mode front_inner_back)
				(layer "Inner"
					(shape circle)
					(size 0.8001 0.8001)
					(clearance 0.1524)
				)
				(layer "B.Cu"
					(shape circle)
					(size 1.0033 1.0033)
					(thermal_gap 0.10795)
					(clearance 0.10795)
				)
			)
		)
		(pad "2" thru_hole circle
			(at -2.54 0 90)
			(size 1.9939 1.9939)
			(drill 0.249936)
			(layers "*.Cu" "*.Mask")
			(remove_unused_layers no)
			(net "T1_GND")
			(clearance 0.10795)
			(padstack
				(mode front_inner_back)
				(layer "Inner"
					(shape circle)
					(size 0.8001 0.8001)
					(clearance 0.1524)
				)
				(layer "B.Cu"
					(shape circle)
					(size 1.9939 1.9939)
					(thermal_gap 0.10795)
					(clearance 0.10795)
				)
			)
		)
		(pad "3" thru_hole circle
			(at -2.54 2.54 90)
			(size 1.9939 1.9939)
			(drill 0.249936)
			(layers "*.Cu" "*.Mask")
			(remove_unused_layers no)
			(net "T1_GND")
			(clearance 0.10795)
			(padstack
				(mode front_inner_back)
				(layer "Inner"
					(shape circle)
					(size 0.8001 0.8001)
					(clearance 0.1524)
				)
				(layer "B.Cu"
					(shape circle)
					(size 1.9939 1.9939)
					(thermal_gap 0.10795)
					(clearance 0.10795)
				)
			)
		)
		(pad "4" thru_hole circle
			(at 0 2.54 90)
			(size 1.0033 1.0033)
			(drill 0.249936)
			(layers "*.Cu" "*.Mask")
			(remove_unused_layers no)
			(net "TDR_DIFF_100_IN4_DP")
			(clearance 0.10795)
			(padstack
				(mode front_inner_back)
				(layer "Inner"
					(shape circle)
					(size 0.8001 0.8001)
					(clearance 0.1524)
				)
				(layer "B.Cu"
					(shape circle)
					(size 1.0033 1.0033)
					(thermal_gap 0.10795)
					(clearance 0.10795)
				)
			)
		)
	)
	(footprint ""
		(layer "B.Cu")
		(at 52.358544 -152.603454)
		(property "Reference" "PR1796"
			(at 0 0 0)
			(layer "B.SilkS")
			(hide yes)
			(effects
				(font
					(size 1.27 1.27)
				)
				(justify mirror)
			)
		)
		(property "Value" ""
			(at 0 0 0)
			(layer "B.Fab")
			(effects
				(font
					(size 1.27 1.27)
				)
				(justify mirror)
			)
		)
		(duplicate_pad_numbers_are_jumpers no)
		(fp_line
			(start -0.7874 -0.4064)
			(end -0.7874 0.4064)
			(stroke
				(width 0.1524)
				(type default)
			)
			(layer "B.SilkS")
		)
		(fp_line
			(start -0.7874 0.4064)
			(end 0.7874 0.4064)
			(stroke
				(width 0.1524)
				(type default)
			)
			(layer "B.SilkS")
		)
		(fp_line
			(start 0.7874 -0.4064)
			(end -0.7874 -0.4064)
			(stroke
				(width 0.1524)
				(type default)
			)
			(layer "B.SilkS")
		)
		(fp_line
			(start 0.7874 0.4064)
			(end 0.7874 -0.4064)
			(stroke
				(width 0.1524)
				(type default)
			)
			(layer "B.SilkS")
		)
		(fp_line
			(start -0.67945 -0.3048)
			(end -0.67945 0.3048)
			(stroke
				(width 0.1)
				(type default)
			)
			(layer "B.Fab")
		)
		(fp_line
			(start -0.67945 0.3048)
			(end -0.120396 0.3048)
			(stroke
				(width 0.1)
				(type default)
			)
			(layer "B.Fab")
		)
		(fp_line
			(start -0.12065 -0.3048)
			(end -0.67945 -0.3048)
			(stroke
				(width 0.1)
				(type default)
			)
			(layer "B.Fab")
		)
		(fp_line
			(start -0.12065 -0.2794)
			(end -0.12065 -0.3048)
			(stroke
				(width 0.1)
				(type default)
			)
			(layer "B.Fab")
		)
		(fp_line
			(start -0.120396 0.2794)
			(end 0.12065 0.2794)
			(stroke
				(width 0.1)
				(type default)
			)
			(layer "B.Fab")
		)
		(fp_line
			(start -0.120396 0.3048)
			(end -0.120396 0.2794)
			(stroke
				(width 0.1)
				(type default)
			)
			(layer "B.Fab")
		)
		(fp_line
			(start 0.12065 -0.305054)
			(end 0.12065 -0.2794)
			(stroke
				(width 0.1)
				(type default)
			)
			(layer "B.Fab")
		)
		(fp_line
			(start 0.12065 -0.2794)
			(end -0.12065 -0.2794)
			(stroke
				(width 0.1)
				(type default)
			)
			(layer "B.Fab")
		)
		(fp_line
			(start 0.12065 0.2794)
			(end 0.12065 0.3048)
			(stroke
				(width 0.1)
				(type default)
			)
			(layer "B.Fab")
		)
		(fp_line
			(start 0.12065 0.3048)
			(end 0.67945 0.3048)
			(stroke
				(width 0.1)
				(type default)
			)
			(layer "B.Fab")
		)
		(fp_line
			(start 0.67945 -0.305054)
			(end 0.12065 -0.305054)
			(stroke
				(width 0.1)
				(type default)
			)
			(layer "B.Fab")
		)
		(fp_line
			(start 0.67945 0.3048)
			(end 0.67945 -0.305054)
			(stroke
				(width 0.1)
				(type default)
			)
			(layer "B.Fab")
		)
		(pad "1" smd circle
			(at 0.40005 0 180)
			(size 0 0)
			(layers "B.Cu" "B.Mask" "B.Paste")
			(net "PVCCINFAON_CPU1_VOS1")
		)
		(pad "2" smd circle
			(at -0.40005 0 180)
			(size 0 0)
			(layers "B.Cu" "B.Mask" "B.Paste")
			(net "PVCCINFAON_CPU1")
		)
	)
)
